# T6G (Grand Teton) — schematic netlist excerpt (pin names and nets, part order shuffled) for the footprints in the layout excerpt that follows; sources: Cadence DE-HDL packaged netlist, KiCad conversion of 04192023_DAF0TMB3IC0_F0TG_MB_C_brd_V02_OCP.brd

C422  Q_CAP  1UF 4V 20% X6S  pkg 0201  page 345 : A = P0V9_CPU1_RT2_2A ; B = GND
C3935  Q_CAP  22UF 4V 20% X6S  pkg C0402  page 70 : A = PVDD11_S3_P0 ; B = GND
C2550  Q_CAP  22UF 4V 20% X6S  pkg C0402  page 70 : A = PVDDCR_SOC_P0 ; B = GND

(kicad_pcb
	(version 20260206)
	(generator "pcbnew")
	(generator_version "10.0")
	(general
		(thickness 1.6)
		(legacy_teardrops no)
	)
	(paper "A4")
	(title_block
		(title "04192023_DAF0TMB3IC0_F0TG_MB_C_brd_V02_OCP.brd")
		(comment 1 "Grand Teton / footprints 5024-5026 of 8354")
	)
	(layers
		(0 "F.Cu" signal "TOP")
		(4 "In1.Cu" signal "GND")
		(6 "In2.Cu" signal "IN1")
		(8 "In3.Cu" signal "GND1")
		(10 "In4.Cu" signal "IN2")
		(12 "In5.Cu" signal "GND2")
		(14 "In6.Cu" signal "IN3")
		(16 "In7.Cu" signal "GND3")
		(18 "In8.Cu" signal "VCC")
		(20 "In9.Cu" signal "VCC1")
		(22 "In10.Cu" signal "GND4")
		(24 "In11.Cu" signal "IN4")
		(26 "In12.Cu" signal "GND5")
		(28 "In13.Cu" signal "IN5")
		(30 "In14.Cu" signal "GND6")
		(32 "In15.Cu" signal "IN6")
		(34 "In16.Cu" signal "GND7")
		(2 "B.Cu" signal "BOTTOM")
		(9 "F.Adhes" user "F.Adhesive")
		(11 "B.Adhes" user "B.Adhesive")
		(13 "F.Paste" user "Package Geometry/Pastemask Top")
		(15 "B.Paste" user "Package Geometry/Pastemask Bottom")
		(5 "F.SilkS" user "Ref Des/Silkscreen Top")
		(7 "B.SilkS" user "Ref Des/Silkscreen Bottom")
		(1 "F.Mask" user "Board Geometry/Soldermask Top")
		(3 "B.Mask" user "Board Geometry/Soldermask Bottom")
		(17 "Dwgs.User" user "User.Drawings")
		(19 "Cmts.User" user "User.Comments")
		(21 "Eco1.User" user "User.Eco1")
		(23 "Eco2.User" user "User.Eco2")
		(25 "Edge.Cuts" user "Board Geometry/Outline")
		(27 "Margin" user)
		(31 "F.CrtYd" user "Package Geometry/Place Bound Top")
		(29 "B.CrtYd" user "Package Geometry/Place Bound Bottom")
		(35 "F.Fab" user "Ref Des/Assembly Top")
		(33 "B.Fab" user "Ref Des/Assembly Bottom")
	)
	(footprint ""
		(layer "B.Cu")
		(at 363.550454 -251.78131)
		(property "Reference" "C2550"
			(at 0 0 0)
			(layer "B.SilkS")
			(hide yes)
			(effects
				(font
					(size 1.27 1.27)
				)
				(justify mirror)
			)
		)
		(property "Value" ""
			(at 0 0 0)
			(layer "B.Fab")
			(effects
				(font
					(size 1.27 1.27)
				)
				(justify mirror)
			)
		)
		(duplicate_pad_numbers_are_jumpers no)
		(fp_line
			(start -0.7874 -0.4064)
			(end -0.7874 0.4064)
			(stroke
				(width 0.1524)
				(type default)
			)
			(layer "B.SilkS")
		)
		(fp_line
			(start -0.7874 0.4064)
			(end 0.7874 0.4064)
			(stroke
				(width 0.1524)
				(type default)
			)
			(layer "B.SilkS")
		)
		(fp_line
			(start 0.7874 -0.4064)
			(end -0.7874 -0.4064)
			(stroke
				(width 0.1524)
				(type default)
			)
			(layer "B.SilkS")
		)
		(fp_line
			(start 0.7874 0.4064)
			(end 0.7874 -0.4064)
			(stroke
				(width 0.1524)
				(type default)
			)
			(layer "B.SilkS")
		)
		(fp_line
			(start -0.67945 -0.3048)
			(end -0.67945 0.3048)
			(stroke
				(width 0.1)
				(type default)
			)
			(layer "B.Fab")
		)
		(fp_line
			(start -0.67945 0.3048)
			(end -0.120396 0.3048)
			(stroke
				(width 0.1)
				(type default)
			)
			(layer "B.Fab")
		)
		(fp_line
			(start -0.12065 -0.3048)
			(end -0.67945 -0.3048)
			(stroke
				(width 0.1)
				(type default)
			)
			(layer "B.Fab")
		)
		(fp_line
			(start -0.12065 -0.2794)
			(end -0.12065 -0.3048)
			(stroke
				(width 0.1)
				(type default)
			)
			(layer "B.Fab")
		)
		(fp_line
			(start -0.120396 0.2794)
			(end 0.12065 0.2794)
			(stroke
				(width 0.1)
				(type default)
			)
			(layer "B.Fab")
		)
		(fp_line
			(start -0.120396 0.3048)
			(end -0.120396 0.2794)
			(stroke
				(width 0.1)
				(type default)
			)
			(layer "B.Fab")
		)
		(fp_line
			(start 0.12065 -0.305054)
			(end 0.12065 -0.2794)
			(stroke
				(width 0.1)
				(type default)
			)
			(layer "B.Fab")
		)
		(fp_line
			(start 0.12065 -0.2794)
			(end -0.12065 -0.2794)
			(stroke
				(width 0.1)
				(type default)
			)
			(layer "B.Fab")
		)
		(fp_line
			(start 0.12065 0.2794)
			(end 0.12065 0.3048)
			(stroke
				(width 0.1)
				(type default)
			)
			(layer "B.Fab")
		)
		(fp_line
			(start 0.12065 0.3048)
			(end 0.67945 0.3048)
			(stroke
				(width 0.1)
				(type default)
			)
			(layer "B.Fab")
		)
		(fp_line
			(start 0.67945 -0.305054)
			(end 0.12065 -0.305054)
			(stroke
				(width 0.1)
				(type default)
			)
			(layer "B.Fab")
		)
		(fp_line
			(start 0.67945 0.3048)
			(end 0.67945 -0.305054)
			(stroke
				(width 0.1)
				(type default)
			)
			(layer "B.Fab")
		)
		(pad "1" smd circle
			(at 0.40005 0 180)
			(size 0 0)
			(layers "B.Cu" "B.Mask" "B.Paste")
			(net "PVDDCR_SOC_P0")
		)
		(pad "2" smd circle
			(at -0.40005 0 180)
			(size 0 0)
			(layers "B.Cu" "B.Mask" "B.Paste")
			(net "GND")
		)
	)
	(footprint ""
		(layer "B.Cu")
		(at 163.806378 -386.766562 90)
		(property "Reference" "C422"
			(at 0 0 90)
			(layer "B.SilkS")
			(hide yes)
			(effects
				(font
					(size 1.27 1.27)
				)
				(justify mirror)
			)
		)
		(property "Value" ""
			(at 0 0 90)
			(layer "B.Fab")
			(effects
				(font
					(size 1.27 1.27)
				)
				(justify mirror)
			)
		)
		(duplicate_pad_numbers_are_jumpers no)
		(fp_line
			(start 0.299974 -0.150114)
			(end -0.299974 -0.150114)
			(stroke
				(width 0.1)
				(type default)
			)
			(layer "B.Fab")
		)
		(fp_line
			(start -0.299974 -0.150114)
			(end -0.299974 0.150114)
			(stroke
				(width 0.1)
				(type default)
			)
			(layer "B.Fab")
		)
		(fp_line
			(start 0.299974 0.150114)
			(end 0.299974 -0.150114)
			(stroke
				(width 0.1)
				(type default)
			)
			(layer "B.Fab")
		)
		(fp_line
			(start -0.299974 0.150114)
			(end 0.299974 0.150114)
			(stroke
				(width 0.1)
				(type default)
			)
			(layer "B.Fab")
		)
		(pad "1" smd rect
			(at 0.2667 0 270)
			(size 0.3048 0.381)
			(layers "B.Cu" "B.Mask" "B.Paste")
			(net "P0V9_CPU1_RT2_2A")
		)
		(pad "2" smd rect
			(at -0.2667 0 270)
			(size 0.3048 0.381)
			(layers "B.Cu" "B.Mask" "B.Paste")
			(net "GND")
		)
	)
	(footprint ""
		(layer "B.Cu")
		(at 353.900232 -262.204962)
		(property "Reference" "C3935"
			(at 0 0 0)
			(layer "B.SilkS")
			(hide yes)
			(effects
				(font
					(size 1.27 1.27)
				)
				(justify mirror)
			)
		)
		(property "Value" ""
			(at 0 0 0)
			(layer "B.Fab")
			(effects
				(font
					(size 1.27 1.27)
				)
				(justify mirror)
			)
		)
		(duplicate_pad_numbers_are_jumpers no)
		(fp_line
			(start -0.7874 -0.4064)
			(end -0.7874 0.4064)
			(stroke
				(width 0.1524)
				(type default)
			)
			(layer "B.SilkS")
		)
		(fp_line
			(start -0.7874 0.4064)
			(end 0.7874 0.4064)
			(stroke
				(width 0.1524)
				(type default)
			)
			(layer "B.SilkS")
		)
		(fp_line
			(start 0.7874 -0.4064)
			(end -0.7874 -0.4064)
			(stroke
				(width 0.1524)
				(type default)
			)
			(layer "B.SilkS")
		)
		(fp_line
			(start 0.7874 0.4064)
			(end 0.7874 -0.4064)
			(stroke
				(width 0.1524)
				(type default)
			)
			(layer "B.SilkS")
		)
		(fp_line
			(start -0.67945 -0.3048)
			(end -0.67945 0.3048)
			(stroke
				(width 0.1)
				(type default)
			)
			(layer "B.Fab")
		)
		(fp_line
			(start -0.67945 0.3048)
			(end -0.120396 0.3048)
			(stroke
				(width 0.1)
				(type default)
			)
			(layer "B.Fab")
		)
		(fp_line
			(start -0.12065 -0.3048)
			(end -0.67945 -0.3048)
			(stroke
				(width 0.1)
				(type default)
			)
			(layer "B.Fab")
		)
		(fp_line
			(start -0.12065 -0.2794)
			(end -0.12065 -0.3048)
			(stroke
				(width 0.1)
				(type default)
			)
			(layer "B.Fab")
		)
		(fp_line
			(start -0.120396 0.2794)
			(end 0.12065 0.2794)
			(stroke
				(width 0.1)
				(type default)
			)
			(layer "B.Fab")
		)
		(fp_line
			(start -0.120396 0.3048)
			(end -0.120396 0.2794)
			(stroke
				(width 0.1)
				(type default)
			)
			(layer "B.Fab")
		)
		(fp_line
			(start 0.12065 -0.305054)
			(end 0.12065 -0.2794)
			(stroke
				(width 0.1)
				(type default)
			)
			(layer "B.Fab")
		)
		(fp_line
			(start 0.12065 -0.2794)
			(end -0.12065 -0.2794)
			(stroke
				(width 0.1)
				(type default)
			)
			(layer "B.Fab")
		)
		(fp_line
			(start 0.12065 0.2794)
			(end 0.12065 0.3048)
			(stroke
				(width 0.1)
				(type default)
			)
			(layer "B.Fab")
		)
		(fp_line
			(start 0.12065 0.3048)
			(end 0.67945 0.3048)
			(stroke
				(width 0.1)
				(type default)
			)
			(layer "B.Fab")
		)
		(fp_line
			(start 0.67945 -0.305054)
			(end 0.12065 -0.305054)
			(stroke
				(width 0.1)
				(type default)
			)
			(layer "B.Fab")
		)
		(fp_line
			(start 0.67945 0.3048)
			(end 0.67945 -0.305054)
			(stroke
				(width 0.1)
				(type default)
			)
			(layer "B.Fab")
		)
		(pad "1" smd circle
			(at 0.40005 0 180)
			(size 0 0)
			(layers "B.Cu" "B.Mask" "B.Paste")
			(net "PVDD11_S3_P0")
		)
		(pad "2" smd circle
			(at -0.40005 0 180)
			(size 0 0)
			(layers "B.Cu" "B.Mask" "B.Paste")
			(net "GND")
		)
	)
)
